(kicad_pcb
	(version 20260206)
	(generator "pcbnew")
	(generator_version "10.0")
	(general
		(thickness 1.6)
		(legacy_teardrops no)
	)
	(paper "A4")
	(title_block
		(title "03242023_DA0F0TMBIJ0_F0T_Motherboard_J_brd_V01_OCP.brd")
		(comment 1 "Grand Teton / footprints 2255-2261 of 6105")
	)
	(layers
		(0 "F.Cu" signal "TOP")
		(4 "In1.Cu" signal "GND")
		(6 "In2.Cu" signal "IN1")
		(8 "In3.Cu" signal "GND1")
		(10 "In4.Cu" signal "IN2")
		(12 "In5.Cu" signal "GND2")
		(14 "In6.Cu" signal "IN3")
		(16 "In7.Cu" signal "GND3")
		(18 "In8.Cu" signal "VCC")
		(20 "In9.Cu" signal "VCC1")
		(22 "In10.Cu" signal "GND4")
		(24 "In11.Cu" signal "IN4")
		(26 "In12.Cu" signal "GND5")
		(28 "In13.Cu" signal "IN5")
		(30 "In14.Cu" signal "GND6")
		(32 "In15.Cu" signal "IN6")
		(34 "In16.Cu" signal "GND7")
		(2 "B.Cu" signal "BOTTOM")
		(9 "F.Adhes" user "F.Adhesive")
		(11 "B.Adhes" user "B.Adhesive")
		(13 "F.Paste" user "Package Geometry/Pastemask Top")
		(15 "B.Paste" user "Package Geometry/Pastemask Bottom")
		(5 "F.SilkS" user "Ref Des/Silkscreen Top")
		(7 "B.SilkS" user "Ref Des/Silkscreen Bottom")
		(1 "F.Mask" user "Board Geometry/Soldermask Top")
		(3 "B.Mask" user "Board Geometry/Soldermask Bottom")
		(17 "Dwgs.User" user "User.Drawings")
		(19 "Cmts.User" user "User.Comments")
		(21 "Eco1.User" user "User.Eco1")
		(23 "Eco2.User" user "User.Eco2")
		(25 "Edge.Cuts" user "Board Geometry/Outline")
		(27 "Margin" user)
		(31 "F.CrtYd" user "Package Geometry/Place Bound Top")
		(29 "B.CrtYd" user "Package Geometry/Place Bound Bottom")
		(35 "F.Fab" user "Ref Des/Assembly Top")
		(33 "B.Fab" user "Ref Des/Assembly Bottom")
	)
	(footprint ""
		(layer "F.Cu")
		(at 264.801858 -73.94067)
		(property "Reference" "PC1222"
			(at 0 0 0)
			(layer "F.SilkS")
			(hide yes)
			(effects
				(font
					(size 1.27 1.27)
				)
			)
		)
		(property "Value" ""
			(at 0 0 0)
			(layer "F.Fab")
			(effects
				(font
					(size 1.27 1.27)
				)
			)
		)
		(duplicate_pad_numbers_are_jumpers no)
		(fp_line
			(start -0.7874 -0.4064)
			(end 0.7874 -0.4064)
			(stroke
				(width 0.1524)
				(type default)
			)
			(layer "F.SilkS")
		)
		(fp_line
			(start -0.7874 0.4064)
			(end -0.7874 -0.4064)
			(stroke
				(width 0.1524)
				(type default)
			)
			(layer "F.SilkS")
		)
		(fp_line
			(start 0.7874 -0.4064)
			(end 0.7874 0.4064)
			(stroke
				(width 0.1524)
				(type default)
			)
			(layer "F.SilkS")
		)
		(fp_line
			(start 0.7874 0.4064)
			(end -0.7874 0.4064)
			(stroke
				(width 0.1524)
				(type default)
			)
			(layer "F.SilkS")
		)
		(fp_line
			(start -0.67945 -0.305054)
			(end -0.12065 -0.305054)
			(stroke
				(width 0.1)
				(type default)
			)
			(layer "F.Fab")
		)
		(fp_line
			(start -0.67945 0.3048)
			(end -0.67945 -0.305054)
			(stroke
				(width 0.1)
				(type default)
			)
			(layer "F.Fab")
		)
		(fp_line
			(start -0.12065 -0.305054)
			(end -0.12065 -0.2794)
			(stroke
				(width 0.1)
				(type default)
			)
			(layer "F.Fab")
		)
		(fp_line
			(start -0.12065 -0.2794)
			(end 0.12065 -0.2794)
			(stroke
				(width 0.1)
				(type default)
			)
			(layer "F.Fab")
		)
		(fp_line
			(start -0.12065 0.2794)
			(end -0.12065 0.3048)
			(stroke
				(width 0.1)
				(type default)
			)
			(layer "F.Fab")
		)
		(fp_line
			(start -0.12065 0.3048)
			(end -0.67945 0.3048)
			(stroke
				(width 0.1)
				(type default)
			)
			(layer "F.Fab")
		)
		(fp_line
			(start 0.120396 0.2794)
			(end -0.12065 0.2794)
			(stroke
				(width 0.1)
				(type default)
			)
			(layer "F.Fab")
		)
		(fp_line
			(start 0.120396 0.3048)
			(end 0.120396 0.2794)
			(stroke
				(width 0.1)
				(type default)
			)
			(layer "F.Fab")
		)
		(fp_line
			(start 0.12065 -0.3048)
			(end 0.67945 -0.3048)
			(stroke
				(width 0.1)
				(type default)
			)
			(layer "F.Fab")
		)
		(fp_line
			(start 0.12065 -0.2794)
			(end 0.12065 -0.3048)
			(stroke
				(width 0.1)
				(type default)
			)
			(layer "F.Fab")
		)
		(fp_line
			(start 0.67945 -0.3048)
			(end 0.67945 0.3048)
			(stroke
				(width 0.1)
				(type default)
			)
			(layer "F.Fab")
		)
		(fp_line
			(start 0.67945 0.3048)
			(end 0.120396 0.3048)
			(stroke
				(width 0.1)
				(type default)
			)
			(layer "F.Fab")
		)
		(pad "1" smd circle
			(at -0.40005 0)
			(size 0 0)
			(layers "F.Cu" "F.Mask" "F.Paste")
			(net "SW_P1V05_PCH_AUX_BST")
		)
		(pad "2" smd circle
			(at 0.40005 0)
			(size 0 0)
			(layers "F.Cu" "F.Mask" "F.Paste")
			(net "SW_P1V05_PCH_AUX_SW")
		)
	)
	(footprint ""
		(layer "F.Cu")
		(at 182.17388 -126.964948 -90)
		(property "Reference" "R274"
			(at 0 0 270)
			(layer "F.SilkS")
			(hide yes)
			(effects
				(font
					(size 1.27 1.27)
				)
			)
		)
		(property "Value" ""
			(at 0 0 270)
			(layer "F.Fab")
			(effects
				(font
					(size 1.27 1.27)
				)
			)
		)
		(duplicate_pad_numbers_are_jumpers no)
		(fp_line
			(start -0.7874 0.4064)
			(end -0.7874 -0.4064)
			(stroke
				(width 0.1524)
				(type default)
			)
			(layer "F.SilkS")
		)
		(fp_line
			(start 0.7874 0.4064)
			(end -0.7874 0.4064)
			(stroke
				(width 0.1524)
				(type default)
			)
			(layer "F.SilkS")
		)
		(fp_line
			(start -0.7874 -0.4064)
			(end 0.7874 -0.4064)
			(stroke
				(width 0.1524)
				(type default)
			)
			(layer "F.SilkS")
		)
		(fp_line
			(start 0.7874 -0.4064)
			(end 0.7874 0.4064)
			(stroke
				(width 0.1524)
				(type default)
			)
			(layer "F.SilkS")
		)
		(fp_line
			(start -0.67945 0.3048)
			(end -0.67945 -0.305054)
			(stroke
				(width 0.1)
				(type default)
			)
			(layer "F.Fab")
		)
		(fp_line
			(start -0.12065 0.3048)
			(end -0.67945 0.3048)
			(stroke
				(width 0.1)
				(type default)
			)
			(layer "F.Fab")
		)
		(fp_line
			(start 0.120396 0.3048)
			(end 0.120396 0.2794)
			(stroke
				(width 0.1)
				(type default)
			)
			(layer "F.Fab")
		)
		(fp_line
			(start 0.67945 0.3048)
			(end 0.120396 0.3048)
			(stroke
				(width 0.1)
				(type default)
			)
			(layer "F.Fab")
		)
		(fp_line
			(start -0.12065 0.2794)
			(end -0.12065 0.3048)
			(stroke
				(width 0.1)
				(type default)
			)
			(layer "F.Fab")
		)
		(fp_line
			(start 0.120396 0.2794)
			(end -0.12065 0.2794)
			(stroke
				(width 0.1)
				(type default)
			)
			(layer "F.Fab")
		)
		(fp_line
			(start -0.12065 -0.2794)
			(end 0.12065 -0.2794)
			(stroke
				(width 0.1)
				(type default)
			)
			(layer "F.Fab")
		)
		(fp_line
			(start 0.12065 -0.2794)
			(end 0.12065 -0.3048)
			(stroke
				(width 0.1)
				(type default)
			)
			(layer "F.Fab")
		)
		(fp_line
			(start 0.12065 -0.3048)
			(end 0.67945 -0.3048)
			(stroke
				(width 0.1)
				(type default)
			)
			(layer "F.Fab")
		)
		(fp_line
			(start 0.67945 -0.3048)
			(end 0.67945 0.3048)
			(stroke
				(width 0.1)
				(type default)
			)
			(layer "F.Fab")
		)
		(fp_line
			(start -0.67945 -0.305054)
			(end -0.12065 -0.305054)
			(stroke
				(width 0.1)
				(type default)
			)
			(layer "F.Fab")
		)
		(fp_line
			(start -0.12065 -0.305054)
			(end -0.12065 -0.2794)
			(stroke
				(width 0.1)
				(type default)
			)
			(layer "F.Fab")
		)
		(pad "1" smd circle
			(at -0.40005 0 270)
			(size 0 0)
			(layers "F.Cu" "F.Mask" "F.Paste")
			(net "P3V3_AUX")
		)
		(pad "2" smd circle
			(at 0.40005 0 270)
			(size 0 0)
			(layers "F.Cu" "F.Mask" "F.Paste")
			(net "FM_CPU1_PROC_ID1")
		)
	)
	(footprint ""
		(layer "F.Cu")
		(at 329.375008 -402.371052 -90)
		(property "Reference" "C1563"
			(at 0 0 270)
			(layer "F.SilkS")
			(hide yes)
			(effects
				(font
					(size 1.27 1.27)
				)
			)
		)
		(property "Value" ""
			(at 0 0 270)
			(layer "F.Fab")
			(effects
				(font
					(size 1.27 1.27)
				)
			)
		)
		(duplicate_pad_numbers_are_jumpers no)
		(fp_line
			(start -0.299974 0.150114)
			(end -0.299974 -0.150114)
			(stroke
				(width 0.1)
				(type default)
			)
			(layer "F.Fab")
		)
		(fp_line
			(start 0.299974 0.150114)
			(end -0.299974 0.150114)
			(stroke
				(width 0.1)
				(type default)
			)
			(layer "F.Fab")
		)
		(fp_line
			(start -0.299974 -0.150114)
			(end 0.299974 -0.150114)
			(stroke
				(width 0.1)
				(type default)
			)
			(layer "F.Fab")
		)
		(fp_line
			(start 0.299974 -0.150114)
			(end 0.299974 0.150114)
			(stroke
				(width 0.1)
				(type default)
			)
			(layer "F.Fab")
		)
		(pad "1" smd rect
			(at -0.2667 0 270)
			(size 0.3048 0.381)
			(layers "F.Cu" "F.Mask" "F.Paste")
			(net "P5E_CPU0_PE4_TX_C_DP<8>")
		)
		(pad "2" smd rect
			(at 0.2667 0 270)
			(size 0.3048 0.381)
			(layers "F.Cu" "F.Mask" "F.Paste")
			(net "P5E_CPU0_PE4_TX_DP<8>")
		)
	)
	(footprint ""
		(layer "F.Cu")
		(at 31.540196 -168.02481)
		(property "Reference" "PC391"
			(at 0 0 0)
			(layer "F.SilkS")
			(hide yes)
			(effects
				(font
					(size 1.27 1.27)
				)
			)
		)
		(property "Value" ""
			(at 0 0 0)
			(layer "F.Fab")
			(effects
				(font
					(size 1.27 1.27)
				)
			)
		)
		(duplicate_pad_numbers_are_jumpers no)
		(fp_line
			(start -0.7874 -0.4064)
			(end 0.7874 -0.4064)
			(stroke
				(width 0.1524)
				(type default)
			)
			(layer "F.SilkS")
		)
		(fp_line
			(start -0.7874 0.4064)
			(end -0.7874 -0.4064)
			(stroke
				(width 0.1524)
				(type default)
			)
			(layer "F.SilkS")
		)
		(fp_line
			(start 0.7874 -0.4064)
			(end 0.7874 0.4064)
			(stroke
				(width 0.1524)
				(type default)
			)
			(layer "F.SilkS")
		)
		(fp_line
			(start 0.7874 0.4064)
			(end -0.7874 0.4064)
			(stroke
				(width 0.1524)
				(type default)
			)
			(layer "F.SilkS")
		)
		(fp_line
			(start -0.67945 -0.305054)
			(end -0.12065 -0.305054)
			(stroke
				(width 0.1)
				(type default)
			)
			(layer "F.Fab")
		)
		(fp_line
			(start -0.67945 0.3048)
			(end -0.67945 -0.305054)
			(stroke
				(width 0.1)
				(type default)
			)
			(layer "F.Fab")
		)
		(fp_line
			(start -0.12065 -0.305054)
			(end -0.12065 -0.2794)
			(stroke
				(width 0.1)
				(type default)
			)
			(layer "F.Fab")
		)
		(fp_line
			(start -0.12065 -0.2794)
			(end 0.12065 -0.2794)
			(stroke
				(width 0.1)
				(type default)
			)
			(layer "F.Fab")
		)
		(fp_line
			(start -0.12065 0.2794)
			(end -0.12065 0.3048)
			(stroke
				(width 0.1)
				(type default)
			)
			(layer "F.Fab")
		)
		(fp_line
			(start -0.12065 0.3048)
			(end -0.67945 0.3048)
			(stroke
				(width 0.1)
				(type default)
			)
			(layer "F.Fab")
		)
		(fp_line
			(start 0.120396 0.2794)
			(end -0.12065 0.2794)
			(stroke
				(width 0.1)
				(type default)
			)
			(layer "F.Fab")
		)
		(fp_line
			(start 0.120396 0.3048)
			(end 0.120396 0.2794)
			(stroke
				(width 0.1)
				(type default)
			)
			(layer "F.Fab")
		)
		(fp_line
			(start 0.12065 -0.3048)
			(end 0.67945 -0.3048)
			(stroke
				(width 0.1)
				(type default)
			)
			(layer "F.Fab")
		)
		(fp_line
			(start 0.12065 -0.2794)
			(end 0.12065 -0.3048)
			(stroke
				(width 0.1)
				(type default)
			)
			(layer "F.Fab")
		)
		(fp_line
			(start 0.67945 -0.3048)
			(end 0.67945 0.3048)
			(stroke
				(width 0.1)
				(type default)
			)
			(layer "F.Fab")
		)
		(fp_line
			(start 0.67945 0.3048)
			(end 0.120396 0.3048)
			(stroke
				(width 0.1)
				(type default)
			)
			(layer "F.Fab")
		)
		(pad "1" smd circle
			(at -0.40005 0)
			(size 0 0)
			(layers "F.Cu" "F.Mask" "F.Paste")
			(net "PVCCD_HV_CPU1_VCC")
		)
		(pad "2" smd circle
			(at 0.40005 0)
			(size 0 0)
			(layers "F.Cu" "F.Mask" "F.Paste")
			(net "GND")
		)
	)
	(footprint ""
		(layer "F.Cu")
		(at 88.655652 -36.288726 180)
		(property "Reference" "R1520"
			(at 0 0 180)
			(layer "F.SilkS")
			(hide yes)
			(effects
				(font
					(size 1.27 1.27)
				)
			)
		)
		(property "Value" ""
			(at 0 0 180)
			(layer "F.Fab")
			(effects
				(font
					(size 1.27 1.27)
				)
			)
		)
		(duplicate_pad_numbers_are_jumpers no)
		(fp_line
			(start 0.7874 0.4064)
			(end -0.7874 0.4064)
			(stroke
				(width 0.1524)
				(type default)
			)
			(layer "F.SilkS")
		)
		(fp_line
			(start 0.7874 -0.4064)
			(end 0.7874 0.4064)
			(stroke
				(width 0.1524)
				(type default)
			)
			(layer "F.SilkS")
		)
		(fp_line
			(start -0.7874 0.4064)
			(end -0.7874 -0.4064)
			(stroke
				(width 0.1524)
				(type default)
			)
			(layer "F.SilkS")
		)
		(fp_line
			(start -0.7874 -0.4064)
			(end 0.7874 -0.4064)
			(stroke
				(width 0.1524)
				(type default)
			)
			(layer "F.SilkS")
		)
		(fp_line
			(start 0.67945 0.3048)
			(end 0.120396 0.3048)
			(stroke
				(width 0.1)
				(type default)
			)
			(layer "F.Fab")
		)
		(fp_line
			(start 0.67945 -0.3048)
			(end 0.67945 0.3048)
			(stroke
				(width 0.1)
				(type default)
			)
			(layer "F.Fab")
		)
		(fp_line
			(start 0.12065 -0.2794)
			(end 0.12065 -0.3048)
			(stroke
				(width 0.1)
				(type default)
			)
			(layer "F.Fab")
		)
		(fp_line
			(start 0.12065 -0.3048)
			(end 0.67945 -0.3048)
			(stroke
				(width 0.1)
				(type default)
			)
			(layer "F.Fab")
		)
		(fp_line
			(start 0.120396 0.3048)
			(end 0.120396 0.2794)
			(stroke
				(width 0.1)
				(type default)
			)
			(layer "F.Fab")
		)
		(fp_line
			(start 0.120396 0.2794)
			(end -0.12065 0.2794)
			(stroke
				(width 0.1)
				(type default)
			)
			(layer "F.Fab")
		)
		(fp_line
			(start -0.12065 0.3048)
			(end -0.67945 0.3048)
			(stroke
				(width 0.1)
				(type default)
			)
			(layer "F.Fab")
		)
		(fp_line
			(start -0.12065 0.2794)
			(end -0.12065 0.3048)
			(stroke
				(width 0.1)
				(type default)
			)
			(layer "F.Fab")
		)
		(fp_line
			(start -0.12065 -0.2794)
			(end 0.12065 -0.2794)
			(stroke
				(width 0.1)
				(type default)
			)
			(layer "F.Fab")
		)
		(fp_line
			(start -0.12065 -0.305054)
			(end -0.12065 -0.2794)
			(stroke
				(width 0.1)
				(type default)
			)
			(layer "F.Fab")
		)
		(fp_line
			(start -0.67945 0.3048)
			(end -0.67945 -0.305054)
			(stroke
				(width 0.1)
				(type default)
			)
			(layer "F.Fab")
		)
		(fp_line
			(start -0.67945 -0.305054)
			(end -0.12065 -0.305054)
			(stroke
				(width 0.1)
				(type default)
			)
			(layer "F.Fab")
		)
		(pad "1" smd circle
			(at -0.40005 0 180)
			(size 0 0)
			(layers "F.Cu" "F.Mask" "F.Paste")
			(net "RST_PCIE_CPU1_DEV_PERST_N")
		)
		(pad "2" smd circle
			(at 0.40005 0 180)
			(size 0 0)
			(layers "F.Cu" "F.Mask" "F.Paste")
			(net "RST_OCP_V3_2_N")
		)
	)
	(footprint ""
		(layer "F.Cu")
		(at 292.62832 -92.260674 180)
		(property "Reference" "R1332"
			(at 0 0 180)
			(layer "F.SilkS")
			(hide yes)
			(effects
				(font
					(size 1.27 1.27)
				)
			)
		)
		(property "Value" ""
			(at 0 0 180)
			(layer "F.Fab")
			(effects
				(font
					(size 1.27 1.27)
				)
			)
		)
		(duplicate_pad_numbers_are_jumpers no)
		(fp_line
			(start 0.7874 0.4064)
			(end -0.7874 0.4064)
			(stroke
				(width 0.1524)
				(type default)
			)
			(layer "F.SilkS")
		)
		(fp_line
			(start 0.7874 -0.4064)
			(end 0.7874 0.4064)
			(stroke
				(width 0.1524)
				(type default)
			)
			(layer "F.SilkS")
		)
		(fp_line
			(start -0.7874 0.4064)
			(end -0.7874 -0.4064)
			(stroke
				(width 0.1524)
				(type default)
			)
			(layer "F.SilkS")
		)
		(fp_line
			(start -0.7874 -0.4064)
			(end 0.7874 -0.4064)
			(stroke
				(width 0.1524)
				(type default)
			)
			(layer "F.SilkS")
		)
		(fp_line
			(start 0.67945 0.3048)
			(end 0.120396 0.3048)
			(stroke
				(width 0.1)
				(type default)
			)
			(layer "F.Fab")
		)
		(fp_line
			(start 0.67945 -0.3048)
			(end 0.67945 0.3048)
			(stroke
				(width 0.1)
				(type default)
			)
			(layer "F.Fab")
		)
		(fp_line
			(start 0.12065 -0.2794)
			(end 0.12065 -0.3048)
			(stroke
				(width 0.1)
				(type default)
			)
			(layer "F.Fab")
		)
		(fp_line
			(start 0.12065 -0.3048)
			(end 0.67945 -0.3048)
			(stroke
				(width 0.1)
				(type default)
			)
			(layer "F.Fab")
		)
		(fp_line
			(start 0.120396 0.3048)
			(end 0.120396 0.2794)
			(stroke
				(width 0.1)
				(type default)
			)
			(layer "F.Fab")
		)
		(fp_line
			(start 0.120396 0.2794)
			(end -0.12065 0.2794)
			(stroke
				(width 0.1)
				(type default)
			)
			(layer "F.Fab")
		)
		(fp_line
			(start -0.12065 0.3048)
			(end -0.67945 0.3048)
			(stroke
				(width 0.1)
				(type default)
			)
			(layer "F.Fab")
		)
		(fp_line
			(start -0.12065 0.2794)
			(end -0.12065 0.3048)
			(stroke
				(width 0.1)
				(type default)
			)
			(layer "F.Fab")
		)
		(fp_line
			(start -0.12065 -0.2794)
			(end 0.12065 -0.2794)
			(stroke
				(width 0.1)
				(type default)
			)
			(layer "F.Fab")
		)
		(fp_line
			(start -0.12065 -0.305054)
			(end -0.12065 -0.2794)
			(stroke
				(width 0.1)
				(type default)
			)
			(layer "F.Fab")
		)
		(fp_line
			(start -0.67945 0.3048)
			(end -0.67945 -0.305054)
			(stroke
				(width 0.1)
				(type default)
			)
			(layer "F.Fab")
		)
		(fp_line
			(start -0.67945 -0.305054)
			(end -0.12065 -0.305054)
			(stroke
				(width 0.1)
				(type default)
			)
			(layer "F.Fab")
		)
		(pad "1" smd circle
			(at -0.40005 0 180)
			(size 0 0)
			(layers "F.Cu" "F.Mask" "F.Paste")
			(net "P3V3_AUX")
		)
		(pad "2" smd circle
			(at 0.40005 0 180)
			(size 0 0)
			(layers "F.Cu" "F.Mask" "F.Paste")
			(net "SMB_FRU_3V3AUX_SDA")
		)
	)
	(footprint ""
		(layer "F.Cu")
		(at 415.818828 -183.032654 180)
		(property "Reference" "PC2946"
			(at 0 0 180)
			(layer "F.SilkS")
			(hide yes)
			(effects
				(font
					(size 1.27 1.27)
				)
			)
		)
		(property "Value" ""
			(at 0 0 180)
			(layer "F.Fab")
			(effects
				(font
					(size 1.27 1.27)
				)
			)
		)
		(duplicate_pad_numbers_are_jumpers no)
		(fp_line
			(start 0.7874 0.4064)
			(end -0.7874 0.4064)
			(stroke
				(width 0.1524)
				(type default)
			)
			(layer "F.SilkS")
		)
		(fp_line
			(start 0.7874 -0.4064)
			(end 0.7874 0.4064)
			(stroke
				(width 0.1524)
				(type default)
			)
			(layer "F.SilkS")
		)
		(fp_line
			(start -0.7874 0.4064)
			(end -0.7874 -0.4064)
			(stroke
				(width 0.1524)
				(type default)
			)
			(layer "F.SilkS")
		)
		(fp_line
			(start -0.7874 -0.4064)
			(end 0.7874 -0.4064)
			(stroke
				(width 0.1524)
				(type default)
			)
			(layer "F.SilkS")
		)
		(fp_line
			(start 0.67945 0.3048)
			(end 0.120396 0.3048)
			(stroke
				(width 0.1)
				(type default)
			)
			(layer "F.Fab")
		)
		(fp_line
			(start 0.67945 -0.3048)
			(end 0.67945 0.3048)
			(stroke
				(width 0.1)
				(type default)
			)
			(layer "F.Fab")
		)
		(fp_line
			(start 0.12065 -0.2794)
			(end 0.12065 -0.3048)
			(stroke
				(width 0.1)
				(type default)
			)
			(layer "F.Fab")
		)
		(fp_line
			(start 0.12065 -0.3048)
			(end 0.67945 -0.3048)
			(stroke
				(width 0.1)
				(type default)
			)
			(layer "F.Fab")
		)
		(fp_line
			(start 0.120396 0.3048)
			(end 0.120396 0.2794)
			(stroke
				(width 0.1)
				(type default)
			)
			(layer "F.Fab")
		)
		(fp_line
			(start 0.120396 0.2794)
			(end -0.12065 0.2794)
			(stroke
				(width 0.1)
				(type default)
			)
			(layer "F.Fab")
		)
		(fp_line
			(start -0.12065 0.3048)
			(end -0.67945 0.3048)
			(stroke
				(width 0.1)
				(type default)
			)
			(layer "F.Fab")
		)
		(fp_line
			(start -0.12065 0.2794)
			(end -0.12065 0.3048)
			(stroke
				(width 0.1)
				(type default)
			)
			(layer "F.Fab")
		)
		(fp_line
			(start -0.12065 -0.2794)
			(end 0.12065 -0.2794)
			(stroke
				(width 0.1)
				(type default)
			)
			(layer "F.Fab")
		)
		(fp_line
			(start -0.12065 -0.305054)
			(end -0.12065 -0.2794)
			(stroke
				(width 0.1)
				(type default)
			)
			(layer "F.Fab")
		)
		(fp_line
			(start -0.67945 0.3048)
			(end -0.67945 -0.305054)
			(stroke
				(width 0.1)
				(type default)
			)
			(layer "F.Fab")
		)
		(fp_line
			(start -0.67945 -0.305054)
			(end -0.12065 -0.305054)
			(stroke
				(width 0.1)
				(type default)
			)
			(layer "F.Fab")
		)
		(pad "1" smd circle
			(at -0.40005 0 180)
			(size 0 0)
			(layers "F.Cu" "F.Mask" "F.Paste")
			(net "PVCCFA_EHV_CPU0_PVCC")
		)
		(pad "2" smd circle
			(at 0.40005 0 180)
			(size 0 0)
			(layers "F.Cu" "F.Mask" "F.Paste")
			(net "GND")
		)
	)
)
